FILE_TYPE = CONNECTIVITY;
{Allegro Design Entry HDL 17.2-2016 S081 (4005846) 1/11/2022}
"PAGE_NUMBER" = 201;
0"NC";
1"GND\g";
2"GND\g";
3"P3V3_STBY\g";
4"GND\g";
5"GND\g";
6"GND\g";
7"GND\g";
8"GND\g";
9"P3V3_STBY\g";
10"P12V_STBY\g";
11"PVDD18_S5_P1_VCC";
12"PVDD18_S5_P1_CS";
13"PVDD18_S5_P1_MODE";
14"PVDD18_S5_P1_EN";
15"GND\g";
16"PVDD18_S5_P1_REF";
17"GND\g";
18"SW_P12V_STBY_PVDD18_S5_P1_FLT";
19"SW_PVDD18_S5_P1_BST";
20"SW_PVDD18_S5_P1_SW";
21"PWRGD_PVDD18_S5_P1";
22"PVDD18_SS_P1_RGND";
23"PVDD18_S5_P1_FB";
24"PVDD18_S5_P1_FB_RC";
25"GND\g";
26"PVDD18_S5_P1\g";
27"VSENSE_PVDD18_S5_P1_DP";
28"VSENSE_PVDD18_S5_P1_DN";
29"PWRGD_PVDD18_S5_R_P1";
%"UNIVERSAL_GND"
"1","(-6425,2800)","0","pure_quanta_power","I10";
;
CDS_LIB"pure_quanta_power"
HDL_POWER"GND";
"A"1;
%"Q_RES"
"2","(-6425,3050)","0","pure_quanta","I11";
;
LOCATION"PR8"
SEC"1"
WATTAGE"1/16W"
MATERIAL"CHIP"
TOLERANCE"1%"
VALUE"8.66K"
PART_NUMBER"CS28662FB14"
PACK_TYPE"0402LF"
CDS_LIB"pure_quanta"
SEC_TYPE"0402LF";
"A"
$PN"1"12;
"B"
$PN"2"1;
%"MPQ8633BGLEC838Z"
"1","(-5475,3900)","0","pure_quanta","I12";
;
LOCATION"PU3"
$SEC"1"
CDS_SEC"1"
PART_TYPE"SMLF"
MATERIAL"IC"
VALUE"MPQ8633BGLE-C838-Z"
PART_NUMBER"AL008633005"
CDS_LMAN_SYM_OUTLINE"-250,725,250,-725"
NEEDS_NO_SIZE"TRUE"
CDS_LIB"pure_quanta";
"VIN2"
$PN"21"18;
"CS"
$PN"3"12;
"MODE"
$PN"4"13;
"TRK_REF"
$PN"5"16;
"SW"
$PN"20"20;
"RGND"
$PN"6"22;
"VCC"
$PN"19"11;
"AGND"
$PN"2"15;
"FB"
$PN"7"23;
"BST"
$PN"1"19;
"EN"
$PN"8"14;
"PGND"
$PN"11_18"15;
"PGOOD"
$PN"9"21;
"VIN1"
$PN"10"18;
%"UNIVERSAL_GND"
"1","(-4925,2950)","0","pure_quanta_power","I13";
;
CDS_LIB"pure_quanta_power"
HDL_POWER"GND";
"A"15;
%"UNIVERSAL_GND"
"1","(-4750,2950)","0","pure_quanta_power","I14";
;
CDS_LIB"pure_quanta_power"
HDL_POWER"GND";
"A"2;
%"Q_CAP"
"1","(-4750,3200)","0","pure_quanta","I15";
;
LOCATION"PC153"
$SEC"1"
CDS_SEC"1"
MATERIAL"X7R"
TOLERANCE"10%"
VALUE"0.022UF"
PART_NUMBER"CH3224K1B01"
VOLTAGE"25V"
PACK_TYPE"0402"
CDS_LIB"pure_quanta";
"B"
$PN"2"2;
"A"
$PN"1"16;
%"Q_RES"
"2","(-3925,3325)","0","pure_quanta","I18";
;
LOCATION"PR147"
$SEC"1"
CDS_SEC"1"
WATTAGE"1/16W"
MATERIAL"CHIP"
TOLERANCE"1%"
VALUE"10K"
PART_NUMBER"TMP_QCS31002FB26"
PACK_TYPE"0402LF"
CDS_LIB"pure_quanta";
"A"
$PN"1"23;
"B"
$PN"2"22;
%"Q_CAP"
"1","(-4200,4225)","0","pure_quanta","I19";
;
LOCATION"PC19"
SEC"1"
MATERIAL"X7R"
TOLERANCE"10%"
VALUE"0.22UF"
PART_NUMBER"CH4223K1B00"
VOLTAGE"16V"
PACK_TYPE"0402"
CDS_LIB"pure_quanta"
SEC_TYPE"0402"
ROOM"VR_CORE1_POWER_STAGE_1";
"B"
$PN"2"20;
"A"
$PN"1"19;
%"Q_CAP"
"1","(-7625,4625)","0","pure_quanta","I20";
;
LOCATION"PC61"
$SEC"1"
CDS_SEC"1"
MATERIAL"X6S"
TOLERANCE"10%"
VALUE"10UF"
PART_NUMBER"CH6104KEA00"
VOLTAGE"25V"
PACK_TYPE"C0805"
CDS_LIB"pure_quanta";
"B"
$PN"2"17;
"A"
$PN"1"18;
%"Q_CAP"
"1","(-7225,4625)","0","pure_quanta","I21";
;
LOCATION"PC150"
$SEC"1"
CDS_SEC"1"
MATERIAL"X6S"
TOLERANCE"10%"
VALUE"10UF"
PART_NUMBER"CH6104KEA00"
VOLTAGE"25V"
PACK_TYPE"C0805"
CDS_LIB"pure_quanta";
"B"
$PN"2"17;
"A"
$PN"1"18;
%"Q_CAP"
"1","(-6775,4625)","0","pure_quanta","I22";
;
LOCATION"PC152"
$SEC"1"
CDS_SEC"1"
MATERIAL"X6S"
TOLERANCE"10%"
VALUE"10UF"
PART_NUMBER"CH6104KEA00"
VOLTAGE"25V"
PACK_TYPE"C0805"
CDS_LIB"pure_quanta";
"B"
$PN"2"17;
"A"
$PN"1"18;
%"Q_CAP"
"1","(-6375,4625)","0","pure_quanta","I23";
;
LOCATION"PC22"
$SEC"1"
CDS_SEC"1"
MATERIAL"X7R"
TOLERANCE"10%"
VALUE"0.1UF"
PART_NUMBER"CH4104K1B00"
VOLTAGE"25V"
PACK_TYPE"0402"
SIGNAL_MODEL"DEFAULT_CAPACITOR_100000PF_2_1"
CDS_LIB"pure_quanta"
ROOM"VR_CORE1_POWER_STAGE_1";
"B"
$PN"2"17;
"A"
$PN"1"18;
%"Q_RES"
"2","(-4425,4875)","0","pure_quanta","I24";
;
LOCATION"PR9"
SEC"1"
WATTAGE"1/16W"
MATERIAL"CHIP"
TOLERANCE"5%"
VALUE"10K"
PART_NUMBER"TMP_QCS31002JB28"
PACK_TYPE"0402LF"
CDS_LIB"pure_quanta"
SEC_TYPE"0402LF";
"A"
$PN"1"3;
"B"
$PN"2"21;
%"UNIVERSAL_POWER"
"1","(-4425,5150)","0","mstr_symbols","I25";
;
HDL_POWER"P3V3_STBY"
CDS_LIB"mstr_symbols";
"A"3;
%"Q_CAP"
"2","(-3325,3350)","0","pure_quanta","I26";
;
LOCATION"PC64"
$SEC"1"
CDS_SEC"1"
MATERIAL"X7R"
TOLERANCE"10%"
VALUE"220PF"
PART_NUMBER"TMP_QCH12206KB14"
VOLTAGE"50V"
PACK_TYPE"0402"
CDS_LIB"pure_quanta";
"A"
$PN"1"23;
"B"
$PN"2"24;
%"Q_RES"
"1","(-3325,3625)","0","pure_quanta","I27";
;
LOCATION"PR148"
$SEC"1"
CDS_SEC"1"
MATERIAL"CHIP"
VALUE"20K"
PART_NUMBER"CS32002FB29"
PACK_TYPE"0402LF"
CDS_LIB"pure_quanta"
WATTAGE"1/16W"
TOLERANCE"1%";
"B"
$PN"2"24;
"A"
$PN"1"23;
%"Q_INDUCTOR"
"1","(-3325,4100)","0","pure_quanta","I28";
;
LOCATION"PL57"
$SEC"1"
CDS_SEC"1"
MATERIAL"IND"
VALUE"1UH"
PART_NUMBER"CV-10B0MZ13"
PACK_TYPE"SMLF"
CDS_LIB"pure_quanta"
NEEDS_NO_SIZE"TRUE";
"1"
$PN"1"20;
"2"
$PN"2"26;
%"Q_INDUCTOR"
"1","(-8500,4875)","0","pure_quanta","I3";
;
LOCATION"PL26"
$SEC"1"
CDS_SEC"1"
MATERIAL"IND"
VALUE"BLM18SN220TN1D/8000MA"
PART_NUMBER"CX220TN1001"
PACK_TYPE"SMLF"
NEEDS_NO_SIZE"TRUE"
CDS_LIB"pure_quanta";
"1"
$PN"1"10;
"2"
$PN"2"18;
%"P1V0"
"1","(0,4600)","0","pure_quanta_power","I35";
;
HDL_POWER"PVDD18_S5_P1"
CDS_LIB"pure_quanta_power";
"A"26;
%"Q_CAP"
"1","(-4325,3375)","1","pure_quanta","I37";
;
LOCATION"PC62"
$SEC"1"
CDS_SEC"1"
MATERIAL"X7R"
TOLERANCE"10%"
VALUE"0.1UF"
PART_NUMBER"CH4104K1B00"
VOLTAGE"25V"
PACK_TYPE"0402"
CDS_LIB"pure_quanta";
"B"
$PN"2"22;
"A"
$PN"1"16;
%"Q_RES"
"1","(-1500,3300)","2","pure_quanta","I38";
;
LOCATION"PR402"
$SEC"1"
CDS_SEC"1"
WATTAGE"1/16W"
MATERIAL"CHIP"
TOLERANCE"1%"
VALUE"49.9"
PART_NUMBER"CS04992FB07"
PACK_TYPE"0402LF"
CDS_LIB"pure_quanta";
"B"
$PN"2"24;
"A"
$PN"1"26;
%"Q_RES"
"1","(-3350,2425)","1","pure_quanta","I39";
;
LOCATION"PR399"
$SEC"1"
CDS_SEC"1"
WATTAGE"1/16W"
MATERIAL"CHIP"
TOLERANCE"1%"
VALUE"49.9"
PART_NUMBER"CS04992FB07"
PACK_TYPE"0402LF"
CDS_LIB"pure_quanta";
"B"
$PN"2"22;
"A"
$PN"1"4;
%"P1V0_AUX"
"1","(-8800,5200)","0","mstr_symbols","I4";
;
HDL_POWER"P12V_STBY"
CDS_LIB"mstr_symbols"
BODY_TYPE"PLUMBING"
VOLTAGE"1.0V"
ROOM"VR_DDR1_POWER_STAGE";
"A"10;
%"Q_RES"
"2","(-2200,2575)","1","pure_quanta","I42";
;
LOCATION"PR401"
$SEC"1"
CDS_SEC"1"
WATTAGE"1/16W"
MATERIAL"CHIP"
TOLERANCE"5%"
VALUE"0"
PART_NUMBER"CS00002JB38"
PACK_TYPE"0402LF"
CDS_LIB"pure_quanta";
"A"
$PN"1"22;
"B"
$PN"2"28;
%"Q_RES"
"1","(-2200,2825)","0","pure_quanta","I43";
;
LOCATION"PR400"
$SEC"1"
CDS_SEC"1"
WATTAGE"1/16W"
MATERIAL"CHIP"
TOLERANCE"1%"
VALUE"10"
PART_NUMBER"CS01002FB07"
PACK_TYPE"0402LF"
CDS_LIB"pure_quanta";
"B"
$PN"2"27;
"A"
$PN"1"24;
%"UNIVERSAL_GND"
"1","(-3350,2200)","0","pure_quanta_power","I44";
;
CDS_LIB"pure_quanta_power"
HDL_POWER"GND";
"A"4;
%"UNIVERSAL_GND"
"1","(0,3525)","0","pure_quanta_power","I45";
;
CDS_LIB"pure_quanta_power"
HDL_POWER"GND";
"A"5;
%"Q_CAP"
"1","(-1300,3825)","0","pure_quanta","I48";
;
LOCATION"PC88"
$SEC"1"
CDS_SEC"1"
MATERIAL"EMPTY"
TOLERANCE"20%"
VALUE"22UF"
VOLTAGE"4V"
PACK_TYPE"0805"
CDS_LIB"pure_quanta"
PART_NUMBER"TMP_QCH622KMEA01";
"B"
$PN"2"25;
"A"
$PN"1"26;
%"Q_CAP"
"1","(-1625,3825)","0","pure_quanta","I49";
;
LOCATION"PC87"
$SEC"1"
CDS_SEC"1"
MATERIAL"EMPTY"
TOLERANCE"20%"
VALUE"22UF"
VOLTAGE"4V"
PACK_TYPE"0805"
CDS_LIB"pure_quanta"
PART_NUMBER"TMP_QCH622KMEA01";
"B"
$PN"2"25;
"A"
$PN"1"26;
%"UNIVERSAL_GND"
"1","(-6925,2825)","0","pure_quanta_power","I5";
;
CDS_LIB"pure_quanta_power"
HDL_POWER"GND";
"A"6;
%"Q_CAP"
"1","(-1875,3825)","0","pure_quanta","I50";
;
LOCATION"PC84"
$SEC"1"
CDS_SEC"1"
MATERIAL"X6S"
TOLERANCE"20%"
VALUE"22UF"
VOLTAGE"4V"
PACK_TYPE"0805"
CDS_LIB"pure_quanta"
PART_NUMBER"TMP_QCH622KMEA01";
"B"
$PN"2"25;
"A"
$PN"1"26;
%"Q_CAP"
"1","(-2075,3825)","0","pure_quanta","I51";
;
LOCATION"PC83"
$SEC"1"
CDS_SEC"1"
MATERIAL"X6S"
TOLERANCE"20%"
VALUE"22UF"
VOLTAGE"4V"
PACK_TYPE"0805"
CDS_LIB"pure_quanta"
PART_NUMBER"TMP_QCH622KMEA01";
"B"
$PN"2"25;
"A"
$PN"1"26;
%"Q_CAP"
"1","(-2500,3825)","0","pure_quanta","I52";
;
LOCATION"PC65"
$SEC"1"
CDS_SEC"1"
MATERIAL"X6S"
TOLERANCE"20%"
VALUE"22UF"
PART_NUMBER"TMP_QCH622KMEA01"
VOLTAGE"4V"
PACK_TYPE"0805"
CDS_LIB"pure_quanta";
"B"
$PN"2"25;
"A"
$PN"1"26;
%"Q_CAP"
"1","(-8075,4625)","0","pure_quanta","I53";
;
LOCATION"PC60"
$SEC"1"
CDS_SEC"1"
MATERIAL"X6S"
TOLERANCE"10%"
VALUE"10UF"
PART_NUMBER"CH6104KEA00"
PACK_TYPE"C0805"
VOLTAGE"25V"
CDS_LIB"pure_quanta";
"B"
$PN"2"17;
"A"
$PN"1"18;
%"Q_RES"
"2","(0,3825)","0","pure_quanta","I55";
;
LOCATION"PR403"
$SEC"1"
CDS_SEC"1"
WATTAGE"1/16W"
MATERIAL"CHIP"
TOLERANCE"1%"
VALUE"1K"
PART_NUMBER"TMP_QCS21002FB24"
PACK_TYPE"0402LF"
CDS_LIB"pure_quanta";
"A"
$PN"1"26;
"B"
$PN"2"5;
%"Q_RES"
"1","(-6900,3875)","0","pure_quanta","I56";
;
LOCATION"PR398"
$SEC"1"
CDS_SEC"1"
WATTAGE"1/16W"
MATERIAL"CHIP"
TOLERANCE"5%"
VALUE"0"
PART_NUMBER"CS00002JB38"
PACK_TYPE"0402LF"
CDS_LIB"pure_quanta";
"B"
$PN"2"13;
"A"
$PN"1"7;
%"UNIVERSAL_GND"
"1","(-7500,3525)","0","pure_quanta_power","I57";
;
CDS_LIB"pure_quanta_power"
HDL_POWER"GND";
"A"7;
%"Q_CAPP"
"1","(-1025,3800)","0","pure_quanta","I59";
;
LOCATION"PC89"
$SEC"1"
CDS_SEC"1"
MATERIAL"OSCON"
TOLERANCE"20%"
VALUE"390UF"
PART_NUMBER"CC7390JMZ12"
VOLTAGE"2.5V"
PACK_TYPE"SMLF"
CDS_LIB"pure_quanta";
"A"
$PN"1"26;
"B"
$PN"2"25;
%"Q_CAP"
"1","(-6925,3110)","2","pure_quanta","I6";
;
LOCATION"PC20"
SEC"1"
MATERIAL"X6S"
TOLERANCE"10%"
VALUE"1UF"
PART_NUMBER"CH5104KEB02"
VOLTAGE"25V"
PACK_TYPE"C0402"
CDS_LIB"pure_quanta"
SIGNAL_MODEL"DEFAULT_CAPACITOR_100000PF_2_1"
SEC_TYPE"C0402"
ROOM"VR_DDR0_CTRL";
"B"
$PN"2"6;
"A"
$PN"1"11;
%"Q_CAP"
"1","(-650,3800)","0","pure_quanta","I60";
;
LOCATION"PC21"
$SEC"1"
CDS_SEC"1"
MATERIAL"X7R"
TOLERANCE"10%"
VALUE"0.1UF"
PART_NUMBER"CH4104K1B00"
VOLTAGE"25V"
PACK_TYPE"0402"
CDS_LIB"pure_quanta";
"B"
$PN"2"25;
"A"
$PN"1"26;
%"UNIVERSAL_GND"
"1","(-650,3450)","0","pure_quanta_power","I61";
;
CDS_LIB"pure_quanta_power"
HDL_POWER"GND";
"A"25;
%"Q_RES"
"1","(-3625,4575)","0","pure_quanta","I62";
;
LOCATION"R259"
$SEC"1"
CDS_SEC"1"
VALUE"33"
BOM_COST"MEM"
CDS_LIB"pure_quanta"
WATTAGE"1/16W"
MATERIAL"CHIP"
TOLERANCE"5%"
PART_NUMBER"CS03302JB29"
PACK_TYPE"0402LF"
ROOM"RST_CPU0_PLD_TO_DIMM";
"B"
$PN"2"29;
"A"
$PN"1"21;
%"Q_CAP"
"1","(-7775,3925)","2","pure_quanta","I64";
;
LOCATION"C675"
$SEC"1"
CDS_SEC"1"
MATERIAL"EMPTY"
TOLERANCE"10%"
VALUE"0.1UF"
PART_NUMBER"CH4104K1B00"
VOLTAGE"25V"
PACK_TYPE"0402"
CDS_LIB"pure_quanta"
ROOM"VR_DDR0_CTRL";
"B"
$PN"2"8;
"A"
$PN"1"14;
%"UNIVERSAL_GND"
"1","(-7775,3725)","0","pure_quanta_power","I65";
;
CDS_LIB"pure_quanta_power"
HDL_POWER"GND";
"A"8;
%"UNIVERSAL_GND"
"1","(-7800,4250)","0","pure_quanta_power","I7";
;
CDS_LIB"pure_quanta_power"
HDL_POWER"GND";
"A"17;
%"Q_RES"
"2","(-6925,3475)","0","pure_quanta","I8";
;
LOCATION"PR397"
$SEC"1"
CDS_SEC"1"
WATTAGE"1/16W"
MATERIAL"CHIP"
TOLERANCE"5%"
VALUE"0"
PART_NUMBER"CS00002JB38"
PACK_TYPE"0402LF"
CDS_LIB"pure_quanta";
"A"
$PN"1"9;
"B"
$PN"2"11;
%"UNIVERSAL_POWER"
"1","(-6925,3675)","0","mstr_symbols","I9";
;
HDL_POWER"P3V3_STBY"
CDS_LIB"mstr_symbols";
"A"9;
END.
